# S9S_MB_2U (Grand Teton) — schematic netlist excerpt (pin names and nets, part order shuffled) for the footprints in the layout excerpt that follows; sources: Cadence DE-HDL packaged netlist, KiCad conversion of 03242023_DA0F0TMBIJ0_F0T_Motherboard_J_brd_V01_OCP.brd

R3285  Q_RES  68K 1% EMPTY  pkg 0402LF  page 166 : A = FM_P2E_SWB ; B = GND
C1024  Q_CAP  22UF 4V 20% X6S  pkg C0402  page 74 : A = PVCCIN_CPU0 ; B = GND

(kicad_pcb
	(version 20260206)
	(generator "pcbnew")
	(generator_version "10.0")
	(general
		(thickness 1.6)
		(legacy_teardrops no)
	)
	(paper "A4")
	(title_block
		(title "03242023_DA0F0TMBIJ0_F0T_Motherboard_J_brd_V01_OCP.brd")
		(comment 1 "Grand Teton / footprints 2616-2617 of 6105")
	)
	(layers
		(0 "F.Cu" signal "TOP")
		(4 "In1.Cu" signal "GND")
		(6 "In2.Cu" signal "IN1")
		(8 "In3.Cu" signal "GND1")
		(10 "In4.Cu" signal "IN2")
		(12 "In5.Cu" signal "GND2")
		(14 "In6.Cu" signal "IN3")
		(16 "In7.Cu" signal "GND3")
		(18 "In8.Cu" signal "VCC")
		(20 "In9.Cu" signal "VCC1")
		(22 "In10.Cu" signal "GND4")
		(24 "In11.Cu" signal "IN4")
		(26 "In12.Cu" signal "GND5")
		(28 "In13.Cu" signal "IN5")
		(30 "In14.Cu" signal "GND6")
		(32 "In15.Cu" signal "IN6")
		(34 "In16.Cu" signal "GND7")
		(2 "B.Cu" signal "BOTTOM")
		(9 "F.Adhes" user "F.Adhesive")
		(11 "B.Adhes" user "B.Adhesive")
		(13 "F.Paste" user "Package Geometry/Pastemask Top")
		(15 "B.Paste" user "Package Geometry/Pastemask Bottom")
		(5 "F.SilkS" user "Ref Des/Silkscreen Top")
		(7 "B.SilkS" user "Ref Des/Silkscreen Bottom")
		(1 "F.Mask" user "Board Geometry/Soldermask Top")
		(3 "B.Mask" user "Board Geometry/Soldermask Bottom")
		(17 "Dwgs.User" user "User.Drawings")
		(19 "Cmts.User" user "User.Comments")
		(21 "Eco1.User" user "User.Eco1")
		(23 "Eco2.User" user "User.Eco2")
		(25 "Edge.Cuts" user "Board Geometry/Outline")
		(27 "Margin" user)
		(31 "F.CrtYd" user "Package Geometry/Place Bound Top")
		(29 "B.CrtYd" user "Package Geometry/Place Bound Bottom")
		(35 "F.Fab" user "Ref Des/Assembly Top")
		(33 "B.Fab" user "Ref Des/Assembly Bottom")
	)
	(footprint ""
		(layer "F.Cu")
		(at 366.48263 -252.956314 -90)
		(property "Reference" "C1024"
			(at 0 0 270)
			(layer "F.SilkS")
			(hide yes)
			(effects
				(font
					(size 1.27 1.27)
				)
			)
		)
		(property "Value" ""
			(at 0 0 270)
			(layer "F.Fab")
			(effects
				(font
					(size 1.27 1.27)
				)
			)
		)
		(duplicate_pad_numbers_are_jumpers no)
		(fp_line
			(start -0.7874 0.4064)
			(end -0.7874 -0.4064)
			(stroke
				(width 0.1524)
				(type default)
			)
			(layer "F.SilkS")
		)
		(fp_line
			(start 0.7874 0.4064)
			(end -0.7874 0.4064)
			(stroke
				(width 0.1524)
				(type default)
			)
			(layer "F.SilkS")
		)
		(fp_line
			(start -0.7874 -0.4064)
			(end 0.7874 -0.4064)
			(stroke
				(width 0.1524)
				(type default)
			)
			(layer "F.SilkS")
		)
		(fp_line
			(start 0.7874 -0.4064)
			(end 0.7874 0.4064)
			(stroke
				(width 0.1524)
				(type default)
			)
			(layer "F.SilkS")
		)
		(fp_line
			(start -0.67945 0.3048)
			(end -0.67945 -0.305054)
			(stroke
				(width 0.1)
				(type default)
			)
			(layer "F.Fab")
		)
		(fp_line
			(start -0.12065 0.3048)
			(end -0.67945 0.3048)
			(stroke
				(width 0.1)
				(type default)
			)
			(layer "F.Fab")
		)
		(fp_line
			(start 0.120396 0.3048)
			(end 0.120396 0.2794)
			(stroke
				(width 0.1)
				(type default)
			)
			(layer "F.Fab")
		)
		(fp_line
			(start 0.67945 0.3048)
			(end 0.120396 0.3048)
			(stroke
				(width 0.1)
				(type default)
			)
			(layer "F.Fab")
		)
		(fp_line
			(start -0.12065 0.2794)
			(end -0.12065 0.3048)
			(stroke
				(width 0.1)
				(type default)
			)
			(layer "F.Fab")
		)
		(fp_line
			(start 0.120396 0.2794)
			(end -0.12065 0.2794)
			(stroke
				(width 0.1)
				(type default)
			)
			(layer "F.Fab")
		)
		(fp_line
			(start -0.12065 -0.2794)
			(end 0.12065 -0.2794)
			(stroke
				(width 0.1)
				(type default)
			)
			(layer "F.Fab")
		)
		(fp_line
			(start 0.12065 -0.2794)
			(end 0.12065 -0.3048)
			(stroke
				(width 0.1)
				(type default)
			)
			(layer "F.Fab")
		)
		(fp_line
			(start 0.12065 -0.3048)
			(end 0.67945 -0.3048)
			(stroke
				(width 0.1)
				(type default)
			)
			(layer "F.Fab")
		)
		(fp_line
			(start 0.67945 -0.3048)
			(end 0.67945 0.3048)
			(stroke
				(width 0.1)
				(type default)
			)
			(layer "F.Fab")
		)
		(fp_line
			(start -0.67945 -0.305054)
			(end -0.12065 -0.305054)
			(stroke
				(width 0.1)
				(type default)
			)
			(layer "F.Fab")
		)
		(fp_line
			(start -0.12065 -0.305054)
			(end -0.12065 -0.2794)
			(stroke
				(width 0.1)
				(type default)
			)
			(layer "F.Fab")
		)
		(pad "1" smd circle
			(at -0.40005 0 270)
			(size 0 0)
			(layers "F.Cu" "F.Mask" "F.Paste")
			(net "PVCCIN_CPU0")
		)
		(pad "2" smd circle
			(at 0.40005 0 270)
			(size 0 0)
			(layers "F.Cu" "F.Mask" "F.Paste")
			(net "GND")
		)
	)
	(footprint ""
		(layer "F.Cu")
		(at 27.628596 -390.294876)
		(property "Reference" "R3285"
			(at 0 0 0)
			(layer "F.SilkS")
			(hide yes)
			(effects
				(font
					(size 1.27 1.27)
				)
			)
		)
		(property "Value" ""
			(at 0 0 0)
			(layer "F.Fab")
			(effects
				(font
					(size 1.27 1.27)
				)
			)
		)
		(duplicate_pad_numbers_are_jumpers no)
		(fp_line
			(start -0.7874 -0.4064)
			(end 0.7874 -0.4064)
			(stroke
				(width 0.1524)
				(type default)
			)
			(layer "F.SilkS")
		)
		(fp_line
			(start -0.7874 0.4064)
			(end -0.7874 -0.4064)
			(stroke
				(width 0.1524)
				(type default)
			)
			(layer "F.SilkS")
		)
		(fp_line
			(start 0.7874 -0.4064)
			(end 0.7874 0.4064)
			(stroke
				(width 0.1524)
				(type default)
			)
			(layer "F.SilkS")
		)
		(fp_line
			(start 0.7874 0.4064)
			(end -0.7874 0.4064)
			(stroke
				(width 0.1524)
				(type default)
			)
			(layer "F.SilkS")
		)
		(fp_line
			(start -0.67945 -0.305054)
			(end -0.12065 -0.305054)
			(stroke
				(width 0.1)
				(type default)
			)
			(layer "F.Fab")
		)
		(fp_line
			(start -0.67945 0.3048)
			(end -0.67945 -0.305054)
			(stroke
				(width 0.1)
				(type default)
			)
			(layer "F.Fab")
		)
		(fp_line
			(start -0.12065 -0.305054)
			(end -0.12065 -0.2794)
			(stroke
				(width 0.1)
				(type default)
			)
			(layer "F.Fab")
		)
		(fp_line
			(start -0.12065 -0.2794)
			(end 0.12065 -0.2794)
			(stroke
				(width 0.1)
				(type default)
			)
			(layer "F.Fab")
		)
		(fp_line
			(start -0.12065 0.2794)
			(end -0.12065 0.3048)
			(stroke
				(width 0.1)
				(type default)
			)
			(layer "F.Fab")
		)
		(fp_line
			(start -0.12065 0.3048)
			(end -0.67945 0.3048)
			(stroke
				(width 0.1)
				(type default)
			)
			(layer "F.Fab")
		)
		(fp_line
			(start 0.120396 0.2794)
			(end -0.12065 0.2794)
			(stroke
				(width 0.1)
				(type default)
			)
			(layer "F.Fab")
		)
		(fp_line
			(start 0.120396 0.3048)
			(end 0.120396 0.2794)
			(stroke
				(width 0.1)
				(type default)
			)
			(layer "F.Fab")
		)
		(fp_line
			(start 0.12065 -0.3048)
			(end 0.67945 -0.3048)
			(stroke
				(width 0.1)
				(type default)
			)
			(layer "F.Fab")
		)
		(fp_line
			(start 0.12065 -0.2794)
			(end 0.12065 -0.3048)
			(stroke
				(width 0.1)
				(type default)
			)
			(layer "F.Fab")
		)
		(fp_line
			(start 0.67945 -0.3048)
			(end 0.67945 0.3048)
			(stroke
				(width 0.1)
				(type default)
			)
			(layer "F.Fab")
		)
		(fp_line
			(start 0.67945 0.3048)
			(end 0.120396 0.3048)
			(stroke
				(width 0.1)
				(type default)
			)
			(layer "F.Fab")
		)
		(pad "1" smd circle
			(at -0.40005 0)
			(size 0 0)
			(layers "F.Cu" "F.Mask" "F.Paste")
			(net "FM_P2E_SWB")
		)
		(pad "2" smd circle
			(at 0.40005 0)
			(size 0 0)
			(layers "F.Cu" "F.Mask" "F.Paste")
			(net "GND")
		)
	)
)
